(kicad_pcb
	(version 20260206)
	(generator "pcbnew")
	(generator_version "10.0")
	(general
		(thickness 1.6)
		(legacy_teardrops no)
	)
	(paper "A4")
	(title_block
		(title "01162023_DA0F0TEBIF0_F0T_Expander_BD_F_brd_V02_OCP.brd")
		(comment 1 "Grand Teton / footprints 1899-1903 of 9728")
	)
	(layers
		(0 "F.Cu" signal "TOP")
		(4 "In1.Cu" signal "GND")
		(6 "In2.Cu" signal "VCC")
		(8 "In3.Cu" signal "VCC1")
		(10 "In4.Cu" signal "GND1")
		(12 "In5.Cu" signal "IN1")
		(14 "In6.Cu" signal "GND2")
		(16 "In7.Cu" signal "IN2")
		(18 "In8.Cu" signal "GND3")
		(20 "In9.Cu" signal "IN3")
		(22 "In10.Cu" signal "GND4")
		(24 "In11.Cu" signal "IN4")
		(26 "In12.Cu" signal "GND5")
		(28 "In13.Cu" signal "IN5")
		(30 "In14.Cu" signal "GND6")
		(32 "In15.Cu" signal "IN6")
		(34 "In16.Cu" signal "GND7")
		(2 "B.Cu" signal "BOTTOM")
		(9 "F.Adhes" user "F.Adhesive")
		(11 "B.Adhes" user "B.Adhesive")
		(13 "F.Paste" user "Package Geometry/Pastemask Top")
		(15 "B.Paste" user "Package Geometry/Pastemask Bottom")
		(5 "F.SilkS" user "Ref Des/Silkscreen Top")
		(7 "B.SilkS" user "Ref Des/Silkscreen Bottom")
		(1 "F.Mask" user "Board Geometry/Soldermask Top")
		(3 "B.Mask" user "Board Geometry/Soldermask Bottom")
		(17 "Dwgs.User" user "User.Drawings")
		(19 "Cmts.User" user "User.Comments")
		(21 "Eco1.User" user "User.Eco1")
		(23 "Eco2.User" user "User.Eco2")
		(25 "Edge.Cuts" user "Board Geometry/Outline")
		(27 "Margin" user)
		(31 "F.CrtYd" user "Package Geometry/Place Bound Top")
		(29 "B.CrtYd" user "Package Geometry/Place Bound Bottom")
		(35 "F.Fab" user "Ref Des/Assembly Top")
		(33 "B.Fab" user "Ref Des/Assembly Bottom")
	)
	(footprint ""
		(layer "F.Cu")
		(at 242.8113 -185.429652 90)
		(property "Reference" "R4250"
			(at 0 0 90)
			(layer "F.SilkS")
			(hide yes)
			(effects
				(font
					(size 1.27 1.27)
				)
			)
		)
		(property "Value" ""
			(at 0 0 90)
			(layer "F.Fab")
			(effects
				(font
					(size 1.27 1.27)
				)
			)
		)
		(duplicate_pad_numbers_are_jumpers no)
		(fp_line
			(start 0.7874 -0.4064)
			(end 0.7874 0.4064)
			(stroke
				(width 0.1524)
				(type default)
			)
			(layer "F.SilkS")
		)
		(fp_line
			(start -0.7874 -0.4064)
			(end 0.7874 -0.4064)
			(stroke
				(width 0.1524)
				(type default)
			)
			(layer "F.SilkS")
		)
		(fp_line
			(start 0.7874 0.4064)
			(end -0.7874 0.4064)
			(stroke
				(width 0.1524)
				(type default)
			)
			(layer "F.SilkS")
		)
		(fp_line
			(start -0.7874 0.4064)
			(end -0.7874 -0.4064)
			(stroke
				(width 0.1524)
				(type default)
			)
			(layer "F.SilkS")
		)
		(fp_line
			(start -0.12065 -0.305054)
			(end -0.12065 -0.2794)
			(stroke
				(width 0.1)
				(type default)
			)
			(layer "F.Fab")
		)
		(fp_line
			(start -0.67945 -0.305054)
			(end -0.12065 -0.305054)
			(stroke
				(width 0.1)
				(type default)
			)
			(layer "F.Fab")
		)
		(fp_line
			(start 0.67945 -0.3048)
			(end 0.67945 0.3048)
			(stroke
				(width 0.1)
				(type default)
			)
			(layer "F.Fab")
		)
		(fp_line
			(start 0.12065 -0.3048)
			(end 0.67945 -0.3048)
			(stroke
				(width 0.1)
				(type default)
			)
			(layer "F.Fab")
		)
		(fp_line
			(start 0.12065 -0.2794)
			(end 0.12065 -0.3048)
			(stroke
				(width 0.1)
				(type default)
			)
			(layer "F.Fab")
		)
		(fp_line
			(start -0.12065 -0.2794)
			(end 0.12065 -0.2794)
			(stroke
				(width 0.1)
				(type default)
			)
			(layer "F.Fab")
		)
		(fp_line
			(start 0.120396 0.2794)
			(end -0.12065 0.2794)
			(stroke
				(width 0.1)
				(type default)
			)
			(layer "F.Fab")
		)
		(fp_line
			(start -0.12065 0.2794)
			(end -0.12065 0.3048)
			(stroke
				(width 0.1)
				(type default)
			)
			(layer "F.Fab")
		)
		(fp_line
			(start 0.67945 0.3048)
			(end 0.120396 0.3048)
			(stroke
				(width 0.1)
				(type default)
			)
			(layer "F.Fab")
		)
		(fp_line
			(start 0.120396 0.3048)
			(end 0.120396 0.2794)
			(stroke
				(width 0.1)
				(type default)
			)
			(layer "F.Fab")
		)
		(fp_line
			(start -0.12065 0.3048)
			(end -0.67945 0.3048)
			(stroke
				(width 0.1)
				(type default)
			)
			(layer "F.Fab")
		)
		(fp_line
			(start -0.67945 0.3048)
			(end -0.67945 -0.305054)
			(stroke
				(width 0.1)
				(type default)
			)
			(layer "F.Fab")
		)
		(pad "1" smd circle
			(at -0.40005 0 90)
			(size 0 0)
			(layers "F.Cu" "F.Mask" "F.Paste")
			(net "BIC_RST_RSMRST_R_N")
		)
		(pad "2" smd circle
			(at 0.40005 0 90)
			(size 0 0)
			(layers "F.Cu" "F.Mask" "F.Paste")
			(net "BIC_RST_RSMRST_N")
		)
	)
	(footprint ""
		(layer "F.Cu")
		(at 33.13557 -308.13375 -135)
		(property "Reference" "R1118"
			(at 0 0 225)
			(layer "F.SilkS")
			(hide yes)
			(effects
				(font
					(size 1.27 1.27)
				)
			)
		)
		(property "Value" ""
			(at 0 0 225)
			(layer "F.Fab")
			(effects
				(font
					(size 1.27 1.27)
				)
			)
		)
		(duplicate_pad_numbers_are_jumpers no)
		(fp_line
			(start 0.787389 0.406267)
			(end -0.787389 0.406267)
			(stroke
				(width 0.1524)
				(type default)
			)
			(layer "F.SilkS")
		)
		(fp_line
			(start 0.787389 -0.406267)
			(end 0.787389 0.406267)
			(stroke
				(width 0.1524)
				(type default)
			)
			(layer "F.SilkS")
		)
		(fp_line
			(start -0.787389 0.406267)
			(end -0.787389 -0.406267)
			(stroke
				(width 0.1524)
				(type default)
			)
			(layer "F.SilkS")
		)
		(fp_line
			(start -0.787389 -0.406267)
			(end 0.787389 -0.406267)
			(stroke
				(width 0.1524)
				(type default)
			)
			(layer "F.SilkS")
		)
		(fp_line
			(start 0.679446 0.30479)
			(end 0.120515 0.30479)
			(stroke
				(width 0.1)
				(type default)
			)
			(layer "F.Fab")
		)
		(fp_line
			(start 0.120515 0.30479)
			(end 0.120335 0.279466)
			(stroke
				(width 0.1)
				(type default)
			)
			(layer "F.Fab")
		)
		(fp_line
			(start 0.120335 0.279466)
			(end -0.120695 0.279466)
			(stroke
				(width 0.1)
				(type default)
			)
			(layer "F.Fab")
		)
		(fp_line
			(start 0.679446 -0.30479)
			(end 0.679446 0.30479)
			(stroke
				(width 0.1)
				(type default)
			)
			(layer "F.Fab")
		)
		(fp_line
			(start -0.120515 0.30479)
			(end -0.679446 0.30479)
			(stroke
				(width 0.1)
				(type default)
			)
			(layer "F.Fab")
		)
		(fp_line
			(start -0.120695 0.279466)
			(end -0.120515 0.30479)
			(stroke
				(width 0.1)
				(type default)
			)
			(layer "F.Fab")
		)
		(fp_line
			(start 0.120695 -0.279466)
			(end 0.120515 -0.30479)
			(stroke
				(width 0.1)
				(type default)
			)
			(layer "F.Fab")
		)
		(fp_line
			(start 0.120515 -0.30479)
			(end 0.679446 -0.30479)
			(stroke
				(width 0.1)
				(type default)
			)
			(layer "F.Fab")
		)
		(fp_line
			(start -0.679446 0.30479)
			(end -0.679446 -0.305149)
			(stroke
				(width 0.1)
				(type default)
			)
			(layer "F.Fab")
		)
		(fp_line
			(start -0.120695 -0.279466)
			(end 0.120695 -0.279466)
			(stroke
				(width 0.1)
				(type default)
			)
			(layer "F.Fab")
		)
		(fp_line
			(start -0.120695 -0.304969)
			(end -0.120695 -0.279466)
			(stroke
				(width 0.1)
				(type default)
			)
			(layer "F.Fab")
		)
		(fp_line
			(start -0.679446 -0.305149)
			(end -0.120695 -0.304969)
			(stroke
				(width 0.1)
				(type default)
			)
			(layer "F.Fab")
		)
		(pad "1" smd circle
			(at -0.40005 0 225)
			(size 0 0)
			(layers "F.Cu" "F.Mask" "F.Paste")
			(net "PEX0_DBG_MODE1")
		)
		(pad "2" smd circle
			(at 0.40005 0 225)
			(size 0 0)
			(layers "F.Cu" "F.Mask" "F.Paste")
			(net "P1V8_PEX")
		)
	)
	(footprint ""
		(layer "F.Cu")
		(at 265.09091 -55.663846 90)
		(property "Reference" "PU64"
			(at -1.083818 2.93878 90)
			(unlocked yes)
			(layer "F.SilkS")
			(effects
				(font
					(size 0.7874 0.5842)
					(thickness 0.1524)
				)
				(justify left)
			)
		)
		(property "Value" ""
			(at 0 0 90)
			(layer "F.Fab")
			(effects
				(font
					(size 1.27 1.27)
				)
			)
		)
		(duplicate_pad_numbers_are_jumpers no)
		(fp_line
			(start 1.943608 -1.549908)
			(end 1.943608 1.549908)
			(stroke
				(width 0.1524)
				(type default)
			)
			(layer "F.SilkS")
		)
		(fp_line
			(start -1.943608 -1.549908)
			(end 1.943608 -1.549908)
			(stroke
				(width 0.1524)
				(type default)
			)
			(layer "F.SilkS")
		)
		(fp_line
			(start 1.943608 1.549908)
			(end -1.943608 1.549908)
			(stroke
				(width 0.1524)
				(type default)
			)
			(layer "F.SilkS")
		)
		(fp_line
			(start -1.943608 1.549908)
			(end -1.943608 -1.549908)
			(stroke
				(width 0.1524)
				(type default)
			)
			(layer "F.SilkS")
		)
		(fp_poly
			(pts
				(xy -2.019808 -1.549908) (xy -1.257808 -1.549908) (xy -1.257808 -1.880108) (xy -2.019808 -1.880108)
			)
			(stroke
				(width 0)
				(type default)
			)
			(fill yes)
			(layer "F.SilkS")
		)
		(fp_line
			(start 1.549908 -1.549908)
			(end 1.549908 1.549908)
			(stroke
				(width 0.1)
				(type default)
			)
			(layer "F.Fab")
		)
		(fp_line
			(start -1.549908 -1.549908)
			(end 1.549908 -1.549908)
			(stroke
				(width 0.1)
				(type default)
			)
			(layer "F.Fab")
		)
		(fp_line
			(start 1.549908 1.549908)
			(end -1.549908 1.549908)
			(stroke
				(width 0.1)
				(type default)
			)
			(layer "F.Fab")
		)
		(fp_line
			(start -1.549908 1.549908)
			(end -1.549908 -1.549908)
			(stroke
				(width 0.1)
				(type default)
			)
			(layer "F.Fab")
		)
		(fp_poly
			(pts
				(xy -2.019808 -1.549908) (xy -1.257808 -1.549908) (xy -1.257808 -1.880108) (xy -2.019808 -1.880108)
			)
			(stroke
				(width 0)
				(type default)
			)
			(fill yes)
			(layer "F.Fab")
		)
		(pad "1" smd rect
			(at -1.500124 -1.249934)
			(size 0.2794 0.6096)
			(layers "F.Cu" "F.Mask" "F.Paste")
			(net "P3V3_SSD9")
		)
		(pad "2" smd rect
			(at -1.500124 -0.750062)
			(size 0.2794 0.6096)
			(layers "F.Cu" "F.Mask" "F.Paste")
			(net "P3V3_SSD9")
		)
		(pad "3" smd rect
			(at -1.500124 -0.249936)
			(size 0.2794 0.6096)
			(layers "F.Cu" "F.Mask" "F.Paste")
			(net "P3V3_SSD9")
		)
		(pad "4" smd rect
			(at -1.500124 0.249936)
			(size 0.2794 0.6096)
			(layers "F.Cu" "F.Mask" "F.Paste")
			(net "P3V3_SSD9")
		)
		(pad "5" smd rect
			(at -1.500124 0.750062)
			(size 0.2794 0.6096)
			(layers "F.Cu" "F.Mask" "F.Paste")
			(net "P3V3_SSD9")
		)
		(pad "6" smd rect
			(at -1.500124 1.249934)
			(size 0.2794 0.6096)
			(layers "F.Cu" "F.Mask" "F.Paste")
			(net "GND")
		)
		(pad "7" smd rect
			(at 1.500124 1.249934)
			(size 0.2794 0.6096)
			(layers "F.Cu" "F.Mask" "F.Paste")
			(net "P3V3_SSD9_SS")
		)
		(pad "8" smd rect
			(at 1.500124 0.750062)
			(size 0.2794 0.6096)
			(layers "F.Cu" "F.Mask" "F.Paste")
			(net "PWRGD_P3V3_SSD9")
		)
		(pad "9" smd rect
			(at 1.500124 0.249936)
			(size 0.2794 0.6096)
			(layers "F.Cu" "F.Mask" "F.Paste")
			(net "P3V3_SSD9_OCP")
		)
		(pad "10" smd rect
			(at 1.500124 -0.249936)
			(size 0.2794 0.6096)
			(layers "F.Cu" "F.Mask" "F.Paste")
			(net "P5V_AUX")
		)
		(pad "11" smd rect
			(at 1.500124 -0.750062)
			(size 0.2794 0.6096)
			(layers "F.Cu" "F.Mask" "F.Paste")
			(net "SSD9_AUX_P3V3_EN_R")
		)
		(pad "12" smd rect
			(at 1.500124 -1.249934)
			(size 0.2794 0.6096)
			(layers "F.Cu" "F.Mask" "F.Paste")
			(net "P3V3_AUX")
		)
		(pad "13" smd rect
			(at 0 0 90)
			(size 1.9812 2.7178)
			(layers "F.Cu" "F.Mask" "F.Paste")
			(net "P3V3_AUX")
		)
		(zone
			(layer "F.Cu")
			(hatch none 0.5)
			(connect_pads
				(clearance 0)
			)
			(min_thickness 0.25)
			(keepout
				(tracks not_allowed)
				(vias allowed)
				(pads allowed)
				(copperpour not_allowed)
				(footprints allowed)
			)
			(placement
				(enabled no)
				(sheetname "")
			)
			(fill
				(thermal_gap 0.5)
				(thermal_bridge_width 0.5)
				(island_removal_mode 0)
			)
			(polygon
				(pts
					(xy 263.54151 -56.806846) (xy 263.66851 -56.806846) (xy 266.64031 -56.806846) (xy 266.640818 -56.806846)
					(xy 266.640818 -54.520846) (xy 266.64031 -54.520846) (xy 266.51331 -54.520846) (xy 265.09091 -54.520846)
					(xy 265.09091 -54.622446) (xy 266.51331 -54.622446) (xy 266.51331 -56.705246) (xy 263.66851 -56.705246)
					(xy 263.66851 -54.622446) (xy 265.06551 -54.622446) (xy 265.06551 -54.520846) (xy 263.66851 -54.520846)
					(xy 263.54151 -54.520846) (xy 263.541002 -54.520846) (xy 263.541002 -56.806846)
				)
			)
		)
	)
	(footprint ""
		(layer "F.Cu")
		(at 227.076 -134.526782 180)
		(property "Reference" "R6302"
			(at 0 0 180)
			(layer "F.SilkS")
			(hide yes)
			(effects
				(font
					(size 1.27 1.27)
				)
			)
		)
		(property "Value" ""
			(at 0 0 180)
			(layer "F.Fab")
			(effects
				(font
					(size 1.27 1.27)
				)
			)
		)
		(duplicate_pad_numbers_are_jumpers no)
		(fp_line
			(start 0.7874 0.4064)
			(end -0.7874 0.4064)
			(stroke
				(width 0.1524)
				(type default)
			)
			(layer "F.SilkS")
		)
		(fp_line
			(start 0.7874 -0.4064)
			(end 0.7874 0.4064)
			(stroke
				(width 0.1524)
				(type default)
			)
			(layer "F.SilkS")
		)
		(fp_line
			(start -0.7874 0.4064)
			(end -0.7874 -0.4064)
			(stroke
				(width 0.1524)
				(type default)
			)
			(layer "F.SilkS")
		)
		(fp_line
			(start -0.7874 -0.4064)
			(end 0.7874 -0.4064)
			(stroke
				(width 0.1524)
				(type default)
			)
			(layer "F.SilkS")
		)
		(fp_line
			(start 0.67945 0.3048)
			(end 0.120396 0.3048)
			(stroke
				(width 0.1)
				(type default)
			)
			(layer "F.Fab")
		)
		(fp_line
			(start 0.67945 -0.3048)
			(end 0.67945 0.3048)
			(stroke
				(width 0.1)
				(type default)
			)
			(layer "F.Fab")
		)
		(fp_line
			(start 0.12065 -0.2794)
			(end 0.12065 -0.3048)
			(stroke
				(width 0.1)
				(type default)
			)
			(layer "F.Fab")
		)
		(fp_line
			(start 0.12065 -0.3048)
			(end 0.67945 -0.3048)
			(stroke
				(width 0.1)
				(type default)
			)
			(layer "F.Fab")
		)
		(fp_line
			(start 0.120396 0.3048)
			(end 0.120396 0.2794)
			(stroke
				(width 0.1)
				(type default)
			)
			(layer "F.Fab")
		)
		(fp_line
			(start 0.120396 0.2794)
			(end -0.12065 0.2794)
			(stroke
				(width 0.1)
				(type default)
			)
			(layer "F.Fab")
		)
		(fp_line
			(start -0.12065 0.3048)
			(end -0.67945 0.3048)
			(stroke
				(width 0.1)
				(type default)
			)
			(layer "F.Fab")
		)
		(fp_line
			(start -0.12065 0.2794)
			(end -0.12065 0.3048)
			(stroke
				(width 0.1)
				(type default)
			)
			(layer "F.Fab")
		)
		(fp_line
			(start -0.12065 -0.2794)
			(end 0.12065 -0.2794)
			(stroke
				(width 0.1)
				(type default)
			)
			(layer "F.Fab")
		)
		(fp_line
			(start -0.12065 -0.305054)
			(end -0.12065 -0.2794)
			(stroke
				(width 0.1)
				(type default)
			)
			(layer "F.Fab")
		)
		(fp_line
			(start -0.67945 0.3048)
			(end -0.67945 -0.305054)
			(stroke
				(width 0.1)
				(type default)
			)
			(layer "F.Fab")
		)
		(fp_line
			(start -0.67945 -0.305054)
			(end -0.12065 -0.305054)
			(stroke
				(width 0.1)
				(type default)
			)
			(layer "F.Fab")
		)
		(pad "1" smd circle
			(at -0.40005 0 180)
			(size 0 0)
			(layers "F.Cu" "F.Mask" "F.Paste")
			(net "SMB_CLK_ISO_R_SCL_R1")
		)
		(pad "2" smd circle
			(at 0.40005 0 180)
			(size 0 0)
			(layers "F.Cu" "F.Mask" "F.Paste")
			(net "SMB_CLK_ISO_R_SCL")
		)
	)
	(footprint ""
		(layer "F.Cu")
		(at 258.44373 -49.95291 180)
		(property "Reference" "R599"
			(at 0 0 180)
			(layer "F.SilkS")
			(hide yes)
			(effects
				(font
					(size 1.27 1.27)
				)
			)
		)
		(property "Value" ""
			(at 0 0 180)
			(layer "F.Fab")
			(effects
				(font
					(size 1.27 1.27)
				)
			)
		)
		(duplicate_pad_numbers_are_jumpers no)
		(fp_line
			(start 0.7874 0.4064)
			(end -0.7874 0.4064)
			(stroke
				(width 0.1524)
				(type default)
			)
			(layer "F.SilkS")
		)
		(fp_line
			(start 0.7874 -0.4064)
			(end 0.7874 0.4064)
			(stroke
				(width 0.1524)
				(type default)
			)
			(layer "F.SilkS")
		)
		(fp_line
			(start -0.7874 0.4064)
			(end -0.7874 -0.4064)
			(stroke
				(width 0.1524)
				(type default)
			)
			(layer "F.SilkS")
		)
		(fp_line
			(start -0.7874 -0.4064)
			(end 0.7874 -0.4064)
			(stroke
				(width 0.1524)
				(type default)
			)
			(layer "F.SilkS")
		)
		(fp_line
			(start 0.67945 0.3048)
			(end 0.120396 0.3048)
			(stroke
				(width 0.1)
				(type default)
			)
			(layer "F.Fab")
		)
		(fp_line
			(start 0.67945 -0.3048)
			(end 0.67945 0.3048)
			(stroke
				(width 0.1)
				(type default)
			)
			(layer "F.Fab")
		)
		(fp_line
			(start 0.12065 -0.2794)
			(end 0.12065 -0.3048)
			(stroke
				(width 0.1)
				(type default)
			)
			(layer "F.Fab")
		)
		(fp_line
			(start 0.12065 -0.3048)
			(end 0.67945 -0.3048)
			(stroke
				(width 0.1)
				(type default)
			)
			(layer "F.Fab")
		)
		(fp_line
			(start 0.120396 0.3048)
			(end 0.120396 0.2794)
			(stroke
				(width 0.1)
				(type default)
			)
			(layer "F.Fab")
		)
		(fp_line
			(start 0.120396 0.2794)
			(end -0.12065 0.2794)
			(stroke
				(width 0.1)
				(type default)
			)
			(layer "F.Fab")
		)
		(fp_line
			(start -0.12065 0.3048)
			(end -0.67945 0.3048)
			(stroke
				(width 0.1)
				(type default)
			)
			(layer "F.Fab")
		)
		(fp_line
			(start -0.12065 0.2794)
			(end -0.12065 0.3048)
			(stroke
				(width 0.1)
				(type default)
			)
			(layer "F.Fab")
		)
		(fp_line
			(start -0.12065 -0.2794)
			(end 0.12065 -0.2794)
			(stroke
				(width 0.1)
				(type default)
			)
			(layer "F.Fab")
		)
		(fp_line
			(start -0.12065 -0.305054)
			(end -0.12065 -0.2794)
			(stroke
				(width 0.1)
				(type default)
			)
			(layer "F.Fab")
		)
		(fp_line
			(start -0.67945 0.3048)
			(end -0.67945 -0.305054)
			(stroke
				(width 0.1)
				(type default)
			)
			(layer "F.Fab")
		)
		(fp_line
			(start -0.67945 -0.305054)
			(end -0.12065 -0.305054)
			(stroke
				(width 0.1)
				(type default)
			)
			(layer "F.Fab")
		)
		(pad "1" smd circle
			(at -0.40005 0 180)
			(size 0 0)
			(layers "F.Cu" "F.Mask" "F.Paste")
			(net "SMB_BIC_I2C6_MUX_SSD_8_15_ADC_R_SCL")
		)
		(pad "2" smd circle
			(at 0.40005 0 180)
			(size 0 0)
			(layers "F.Cu" "F.Mask" "F.Paste")
			(net "SMB_SSD8_ADC_SCL")
		)
	)
)
